# S9S_MB_2U (Grand Teton) — schematic netlist excerpt (pin names and nets, part order shuffled) for the footprints in the layout excerpt that follows; sources: Cadence DE-HDL packaged netlist, KiCad conversion of 03242023_DA0F0TMBIJ0_F0T_Motherboard_J_brd_V01_OCP.brd

R321  Q_RES  10K 1% CHIP  pkg 0402LF  page 80 : A = P3V3_AUX ; B = FM_S3M_CPU0_CPLD_CONFIG_N
PR159  Q_RES  28K 1% EMPTY  pkg 0402LF  page 266 : A = PVCCIN_CPU0_VREF ; B = PVCCIN_CPU0_ADDR

(kicad_pcb
	(version 20260206)
	(generator "pcbnew")
	(generator_version "10.0")
	(general
		(thickness 1.6)
		(legacy_teardrops no)
	)
	(paper "A4")
	(title_block
		(title "03242023_DA0F0TMBIJ0_F0T_Motherboard_J_brd_V01_OCP.brd")
		(comment 1 "Grand Teton / footprints 4509-4510 of 6105")
	)
	(layers
		(0 "F.Cu" signal "TOP")
		(4 "In1.Cu" signal "GND")
		(6 "In2.Cu" signal "IN1")
		(8 "In3.Cu" signal "GND1")
		(10 "In4.Cu" signal "IN2")
		(12 "In5.Cu" signal "GND2")
		(14 "In6.Cu" signal "IN3")
		(16 "In7.Cu" signal "GND3")
		(18 "In8.Cu" signal "VCC")
		(20 "In9.Cu" signal "VCC1")
		(22 "In10.Cu" signal "GND4")
		(24 "In11.Cu" signal "IN4")
		(26 "In12.Cu" signal "GND5")
		(28 "In13.Cu" signal "IN5")
		(30 "In14.Cu" signal "GND6")
		(32 "In15.Cu" signal "IN6")
		(34 "In16.Cu" signal "GND7")
		(2 "B.Cu" signal "BOTTOM")
		(9 "F.Adhes" user "F.Adhesive")
		(11 "B.Adhes" user "B.Adhesive")
		(13 "F.Paste" user "Package Geometry/Pastemask Top")
		(15 "B.Paste" user "Package Geometry/Pastemask Bottom")
		(5 "F.SilkS" user "Ref Des/Silkscreen Top")
		(7 "B.SilkS" user "Ref Des/Silkscreen Bottom")
		(1 "F.Mask" user "Board Geometry/Soldermask Top")
		(3 "B.Mask" user "Board Geometry/Soldermask Bottom")
		(17 "Dwgs.User" user "User.Drawings")
		(19 "Cmts.User" user "User.Comments")
		(21 "Eco1.User" user "User.Eco1")
		(23 "Eco2.User" user "User.Eco2")
		(25 "Edge.Cuts" user "Board Geometry/Outline")
		(27 "Margin" user)
		(31 "F.CrtYd" user "Package Geometry/Place Bound Top")
		(29 "B.CrtYd" user "Package Geometry/Place Bound Bottom")
		(35 "F.Fab" user "Ref Des/Assembly Top")
		(33 "B.Fab" user "Ref Des/Assembly Bottom")
	)
	(footprint ""
		(layer "B.Cu")
		(at 362.56341 -357.690166)
		(property "Reference" "PR159"
			(at 0 0 0)
			(layer "B.SilkS")
			(hide yes)
			(effects
				(font
					(size 1.27 1.27)
				)
				(justify mirror)
			)
		)
		(property "Value" ""
			(at 0 0 0)
			(layer "B.Fab")
			(effects
				(font
					(size 1.27 1.27)
				)
				(justify mirror)
			)
		)
		(duplicate_pad_numbers_are_jumpers no)
		(fp_line
			(start -0.7874 -0.4064)
			(end -0.7874 0.4064)
			(stroke
				(width 0.1524)
				(type default)
			)
			(layer "B.SilkS")
		)
		(fp_line
			(start -0.7874 0.4064)
			(end 0.7874 0.4064)
			(stroke
				(width 0.1524)
				(type default)
			)
			(layer "B.SilkS")
		)
		(fp_line
			(start 0.7874 -0.4064)
			(end -0.7874 -0.4064)
			(stroke
				(width 0.1524)
				(type default)
			)
			(layer "B.SilkS")
		)
		(fp_line
			(start 0.7874 0.4064)
			(end 0.7874 -0.4064)
			(stroke
				(width 0.1524)
				(type default)
			)
			(layer "B.SilkS")
		)
		(fp_line
			(start -0.67945 -0.3048)
			(end -0.67945 0.3048)
			(stroke
				(width 0.1)
				(type default)
			)
			(layer "B.Fab")
		)
		(fp_line
			(start -0.67945 0.3048)
			(end -0.120396 0.3048)
			(stroke
				(width 0.1)
				(type default)
			)
			(layer "B.Fab")
		)
		(fp_line
			(start -0.12065 -0.3048)
			(end -0.67945 -0.3048)
			(stroke
				(width 0.1)
				(type default)
			)
			(layer "B.Fab")
		)
		(fp_line
			(start -0.12065 -0.2794)
			(end -0.12065 -0.3048)
			(stroke
				(width 0.1)
				(type default)
			)
			(layer "B.Fab")
		)
		(fp_line
			(start -0.120396 0.2794)
			(end 0.12065 0.2794)
			(stroke
				(width 0.1)
				(type default)
			)
			(layer "B.Fab")
		)
		(fp_line
			(start -0.120396 0.3048)
			(end -0.120396 0.2794)
			(stroke
				(width 0.1)
				(type default)
			)
			(layer "B.Fab")
		)
		(fp_line
			(start 0.12065 -0.305054)
			(end 0.12065 -0.2794)
			(stroke
				(width 0.1)
				(type default)
			)
			(layer "B.Fab")
		)
		(fp_line
			(start 0.12065 -0.2794)
			(end -0.12065 -0.2794)
			(stroke
				(width 0.1)
				(type default)
			)
			(layer "B.Fab")
		)
		(fp_line
			(start 0.12065 0.2794)
			(end 0.12065 0.3048)
			(stroke
				(width 0.1)
				(type default)
			)
			(layer "B.Fab")
		)
		(fp_line
			(start 0.12065 0.3048)
			(end 0.67945 0.3048)
			(stroke
				(width 0.1)
				(type default)
			)
			(layer "B.Fab")
		)
		(fp_line
			(start 0.67945 -0.305054)
			(end 0.12065 -0.305054)
			(stroke
				(width 0.1)
				(type default)
			)
			(layer "B.Fab")
		)
		(fp_line
			(start 0.67945 0.3048)
			(end 0.67945 -0.305054)
			(stroke
				(width 0.1)
				(type default)
			)
			(layer "B.Fab")
		)
		(pad "1" smd circle
			(at 0.40005 0 180)
			(size 0 0)
			(layers "B.Cu" "B.Mask" "B.Paste")
			(net "PVCCIN_CPU0_VREF")
		)
		(pad "2" smd circle
			(at -0.40005 0 180)
			(size 0 0)
			(layers "B.Cu" "B.Mask" "B.Paste")
			(net "PVCCIN_CPU0_ADDR")
		)
	)
	(footprint ""
		(layer "B.Cu")
		(at 416.287712 -193.08953 -90)
		(property "Reference" "R321"
			(at 0 0 90)
			(layer "B.SilkS")
			(hide yes)
			(effects
				(font
					(size 1.27 1.27)
				)
				(justify mirror)
			)
		)
		(property "Value" ""
			(at 0 0 90)
			(layer "B.Fab")
			(effects
				(font
					(size 1.27 1.27)
				)
				(justify mirror)
			)
		)
		(duplicate_pad_numbers_are_jumpers no)
		(fp_line
			(start -0.7874 0.4064)
			(end 0.7874 0.4064)
			(stroke
				(width 0.1524)
				(type default)
			)
			(layer "B.SilkS")
		)
		(fp_line
			(start 0.7874 0.4064)
			(end 0.7874 -0.4064)
			(stroke
				(width 0.1524)
				(type default)
			)
			(layer "B.SilkS")
		)
		(fp_line
			(start -0.7874 -0.4064)
			(end -0.7874 0.4064)
			(stroke
				(width 0.1524)
				(type default)
			)
			(layer "B.SilkS")
		)
		(fp_line
			(start 0.7874 -0.4064)
			(end -0.7874 -0.4064)
			(stroke
				(width 0.1524)
				(type default)
			)
			(layer "B.SilkS")
		)
		(fp_line
			(start -0.67945 0.3048)
			(end -0.120396 0.3048)
			(stroke
				(width 0.1)
				(type default)
			)
			(layer "B.Fab")
		)
		(fp_line
			(start -0.120396 0.3048)
			(end -0.120396 0.2794)
			(stroke
				(width 0.1)
				(type default)
			)
			(layer "B.Fab")
		)
		(fp_line
			(start 0.12065 0.3048)
			(end 0.67945 0.3048)
			(stroke
				(width 0.1)
				(type default)
			)
			(layer "B.Fab")
		)
		(fp_line
			(start 0.67945 0.3048)
			(end 0.67945 -0.305054)
			(stroke
				(width 0.1)
				(type default)
			)
			(layer "B.Fab")
		)
		(fp_line
			(start -0.120396 0.2794)
			(end 0.12065 0.2794)
			(stroke
				(width 0.1)
				(type default)
			)
			(layer "B.Fab")
		)
		(fp_line
			(start 0.12065 0.2794)
			(end 0.12065 0.3048)
			(stroke
				(width 0.1)
				(type default)
			)
			(layer "B.Fab")
		)
		(fp_line
			(start -0.12065 -0.2794)
			(end -0.12065 -0.3048)
			(stroke
				(width 0.1)
				(type default)
			)
			(layer "B.Fab")
		)
		(fp_line
			(start 0.12065 -0.2794)
			(end -0.12065 -0.2794)
			(stroke
				(width 0.1)
				(type default)
			)
			(layer "B.Fab")
		)
		(fp_line
			(start -0.67945 -0.3048)
			(end -0.67945 0.3048)
			(stroke
				(width 0.1)
				(type default)
			)
			(layer "B.Fab")
		)
		(fp_line
			(start -0.12065 -0.3048)
			(end -0.67945 -0.3048)
			(stroke
				(width 0.1)
				(type default)
			)
			(layer "B.Fab")
		)
		(fp_line
			(start 0.12065 -0.305054)
			(end 0.12065 -0.2794)
			(stroke
				(width 0.1)
				(type default)
			)
			(layer "B.Fab")
		)
		(fp_line
			(start 0.67945 -0.305054)
			(end 0.12065 -0.305054)
			(stroke
				(width 0.1)
				(type default)
			)
			(layer "B.Fab")
		)
		(pad "1" smd circle
			(at 0.40005 0 90)
			(size 0 0)
			(layers "B.Cu" "B.Mask" "B.Paste")
			(net "P3V3_AUX")
		)
		(pad "2" smd circle
			(at -0.40005 0 90)
			(size 0 0)
			(layers "B.Cu" "B.Mask" "B.Paste")
			(net "FM_S3M_CPU0_CPLD_CONFIG_N")
		)
	)
)
